# T6G (Grand Teton) — schematic netlist excerpt (pin names and nets, part order shuffled) for the footprints in the layout excerpt that follows; sources: Cadence DE-HDL packaged netlist, KiCad conversion of 04192023_DAF0TMB3IC0_F0TG_MB_C_brd_V02_OCP.brd

PC6810  Q_CAPP  100UF 16V 20% OSCON  pkg SMLF  page 363 : A = SW_P12V_AUX_P0V9_RETIMER_CPU0_FLT ; B = GND
C2434  Q_CAP  22UF 4V 20% X6S  pkg C0402  page 74 : A = PVDDCR_SOC_P1 ; B = GND

(kicad_pcb
	(version 20260206)
	(generator "pcbnew")
	(generator_version "10.0")
	(general
		(thickness 1.6)
		(legacy_teardrops no)
	)
	(paper "A4")
	(title_block
		(title "04192023_DAF0TMB3IC0_F0TG_MB_C_brd_V02_OCP.brd")
		(comment 1 "Grand Teton / footprints 4512-4513 of 8354")
	)
	(layers
		(0 "F.Cu" signal "TOP")
		(4 "In1.Cu" signal "GND")
		(6 "In2.Cu" signal "IN1")
		(8 "In3.Cu" signal "GND1")
		(10 "In4.Cu" signal "IN2")
		(12 "In5.Cu" signal "GND2")
		(14 "In6.Cu" signal "IN3")
		(16 "In7.Cu" signal "GND3")
		(18 "In8.Cu" signal "VCC")
		(20 "In9.Cu" signal "VCC1")
		(22 "In10.Cu" signal "GND4")
		(24 "In11.Cu" signal "IN4")
		(26 "In12.Cu" signal "GND5")
		(28 "In13.Cu" signal "IN5")
		(30 "In14.Cu" signal "GND6")
		(32 "In15.Cu" signal "IN6")
		(34 "In16.Cu" signal "GND7")
		(2 "B.Cu" signal "BOTTOM")
		(9 "F.Adhes" user "F.Adhesive")
		(11 "B.Adhes" user "B.Adhesive")
		(13 "F.Paste" user "Package Geometry/Pastemask Top")
		(15 "B.Paste" user "Package Geometry/Pastemask Bottom")
		(5 "F.SilkS" user "Ref Des/Silkscreen Top")
		(7 "B.SilkS" user "Ref Des/Silkscreen Bottom")
		(1 "F.Mask" user "Board Geometry/Soldermask Top")
		(3 "B.Mask" user "Board Geometry/Soldermask Bottom")
		(17 "Dwgs.User" user "User.Drawings")
		(19 "Cmts.User" user "User.Comments")
		(21 "Eco1.User" user "User.Eco1")
		(23 "Eco2.User" user "User.Eco2")
		(25 "Edge.Cuts" user "Board Geometry/Outline")
		(27 "Margin" user)
		(31 "F.CrtYd" user "Package Geometry/Place Bound Top")
		(29 "B.CrtYd" user "Package Geometry/Place Bound Bottom")
		(35 "F.Fab" user "Ref Des/Assembly Top")
		(33 "B.Fab" user "Ref Des/Assembly Bottom")
	)
	(footprint ""
		(layer "F.Cu")
		(at 115.275868 -256.012442 90)
		(property "Reference" "C2434"
			(at 0 0 90)
			(layer "F.SilkS")
			(hide yes)
			(effects
				(font
					(size 1.27 1.27)
				)
			)
		)
		(property "Value" ""
			(at 0 0 90)
			(layer "F.Fab")
			(effects
				(font
					(size 1.27 1.27)
				)
			)
		)
		(duplicate_pad_numbers_are_jumpers no)
		(fp_line
			(start 0.7874 -0.4064)
			(end 0.7874 0.4064)
			(stroke
				(width 0.1524)
				(type default)
			)
			(layer "F.SilkS")
		)
		(fp_line
			(start -0.7874 -0.4064)
			(end 0.7874 -0.4064)
			(stroke
				(width 0.1524)
				(type default)
			)
			(layer "F.SilkS")
		)
		(fp_line
			(start 0.7874 0.4064)
			(end -0.7874 0.4064)
			(stroke
				(width 0.1524)
				(type default)
			)
			(layer "F.SilkS")
		)
		(fp_line
			(start -0.7874 0.4064)
			(end -0.7874 -0.4064)
			(stroke
				(width 0.1524)
				(type default)
			)
			(layer "F.SilkS")
		)
		(fp_line
			(start -0.12065 -0.305054)
			(end -0.12065 -0.2794)
			(stroke
				(width 0.1)
				(type default)
			)
			(layer "F.Fab")
		)
		(fp_line
			(start -0.67945 -0.305054)
			(end -0.12065 -0.305054)
			(stroke
				(width 0.1)
				(type default)
			)
			(layer "F.Fab")
		)
		(fp_line
			(start 0.67945 -0.3048)
			(end 0.67945 0.3048)
			(stroke
				(width 0.1)
				(type default)
			)
			(layer "F.Fab")
		)
		(fp_line
			(start 0.12065 -0.3048)
			(end 0.67945 -0.3048)
			(stroke
				(width 0.1)
				(type default)
			)
			(layer "F.Fab")
		)
		(fp_line
			(start 0.12065 -0.2794)
			(end 0.12065 -0.3048)
			(stroke
				(width 0.1)
				(type default)
			)
			(layer "F.Fab")
		)
		(fp_line
			(start -0.12065 -0.2794)
			(end 0.12065 -0.2794)
			(stroke
				(width 0.1)
				(type default)
			)
			(layer "F.Fab")
		)
		(fp_line
			(start 0.120396 0.2794)
			(end -0.12065 0.2794)
			(stroke
				(width 0.1)
				(type default)
			)
			(layer "F.Fab")
		)
		(fp_line
			(start -0.12065 0.2794)
			(end -0.12065 0.3048)
			(stroke
				(width 0.1)
				(type default)
			)
			(layer "F.Fab")
		)
		(fp_line
			(start 0.67945 0.3048)
			(end 0.120396 0.3048)
			(stroke
				(width 0.1)
				(type default)
			)
			(layer "F.Fab")
		)
		(fp_line
			(start 0.120396 0.3048)
			(end 0.120396 0.2794)
			(stroke
				(width 0.1)
				(type default)
			)
			(layer "F.Fab")
		)
		(fp_line
			(start -0.12065 0.3048)
			(end -0.67945 0.3048)
			(stroke
				(width 0.1)
				(type default)
			)
			(layer "F.Fab")
		)
		(fp_line
			(start -0.67945 0.3048)
			(end -0.67945 -0.305054)
			(stroke
				(width 0.1)
				(type default)
			)
			(layer "F.Fab")
		)
		(pad "1" smd circle
			(at -0.40005 0 90)
			(size 0 0)
			(layers "F.Cu" "F.Mask" "F.Paste")
			(net "PVDDCR_SOC_P1")
		)
		(pad "2" smd circle
			(at 0.40005 0 90)
			(size 0 0)
			(layers "F.Cu" "F.Mask" "F.Paste")
			(net "GND")
		)
	)
	(footprint ""
		(layer "F.Cu")
		(at 458.661008 -411.8737)
		(property "Reference" "PC6810"
			(at -1.969008 -3.64363 0)
			(unlocked yes)
			(layer "F.SilkS")
			(effects
				(font
					(size 0.7874 0.5842)
					(thickness 0.1524)
				)
				(justify left)
			)
		)
		(property "Value" ""
			(at 0 0 0)
			(layer "F.Fab")
			(effects
				(font
					(size 1.27 1.27)
				)
			)
		)
		(duplicate_pad_numbers_are_jumpers no)
		(fp_line
			(start -2.750058 -1.988058)
			(end -2.750058 -0.9398)
			(stroke
				(width 0.1524)
				(type default)
			)
			(layer "F.SilkS")
		)
		(fp_line
			(start -2.750058 0.9398)
			(end -2.750058 1.988058)
			(stroke
				(width 0.1524)
				(type default)
			)
			(layer "F.SilkS")
		)
		(fp_line
			(start -2.750058 1.988058)
			(end -1.988058 2.750058)
			(stroke
				(width 0.1524)
				(type default)
			)
			(layer "F.SilkS")
		)
		(fp_line
			(start -1.988058 -2.750058)
			(end -2.750058 -1.988058)
			(stroke
				(width 0.1524)
				(type default)
			)
			(layer "F.SilkS")
		)
		(fp_line
			(start -1.988058 2.750058)
			(end 2.750058 2.750058)
			(stroke
				(width 0.1524)
				(type default)
			)
			(layer "F.SilkS")
		)
		(fp_line
			(start 2.750058 -2.750058)
			(end -1.988058 -2.750058)
			(stroke
				(width 0.1524)
				(type default)
			)
			(layer "F.SilkS")
		)
		(fp_line
			(start 2.750058 -0.9398)
			(end 2.750058 -2.750058)
			(stroke
				(width 0.1524)
				(type default)
			)
			(layer "F.SilkS")
		)
		(fp_line
			(start 2.750058 2.750058)
			(end 2.750058 0.9398)
			(stroke
				(width 0.1524)
				(type default)
			)
			(layer "F.SilkS")
		)
		(fp_line
			(start -2.750058 -2.750058)
			(end -2.750058 2.750058)
			(stroke
				(width 0.1)
				(type default)
			)
			(layer "F.Fab")
		)
		(fp_line
			(start -2.750058 2.750058)
			(end 2.750058 2.750058)
			(stroke
				(width 0.1)
				(type default)
			)
			(layer "F.Fab")
		)
		(fp_line
			(start 2.750058 -2.750058)
			(end -2.750058 -2.750058)
			(stroke
				(width 0.1)
				(type default)
			)
			(layer "F.Fab")
		)
		(fp_line
			(start 2.750058 2.750058)
			(end 2.750058 -2.750058)
			(stroke
				(width 0.1)
				(type default)
			)
			(layer "F.Fab")
		)
		(pad "1" smd rect
			(at -2.199894 0 90)
			(size 1.6002 3.0226)
			(layers "F.Cu" "F.Mask" "F.Paste")
			(net "SW_P12V_AUX_P0V9_RETIMER_CPU0_FLT")
		)
		(pad "2" smd rect
			(at 2.199894 0 90)
			(size 1.6002 3.0226)
			(layers "F.Cu" "F.Mask" "F.Paste")
			(net "GND")
		)
	)
)
